FILE_TYPE = CONNECTIVITY;
{Allegro Design Entry HDL 16.6-p007 (v16-6-112F) 10/10/2012}
"PAGE_NUMBER" = 166;
0"NC";
1"PVCCIO_CPU0\g";
2"GND\g";
3"GND\g";
4"P3V3_STBY\g";
5"GND\g";
6"GND\g";
7"P3V3_STBY\g";
8"PECI_PCH";
9"PECI_BMC";
10"PECI_CPU_G";
11"PECI_SEL";
%"RES"
"2","(-5050,3500)","2","mstr_discrete","I28";
;
CDS_SEC"1"
TOLERANCE"1%"
MATERIAL"CHIP"
PACK_TYPE"0402"
PART_NUMBER"G21796-072"
VALUE"4.75K"
WATTAGE"1/16W"
LOCATION"R7C17"
CDS_LIB"mstr_discrete"
ROOM"PECI"
CDS_LOCATION"R7C17"
SEC"1"
SEC_TYPE"0402"
BOM_COST"DEBUG";
"A"
$PN"1"1;
"B"
$PN"2"9;
%"PVCCIO_CPU0"
"1","(-5050,3775)","0","mstr_symbols","I31";
;
CDS_LIB"mstr_symbols"
HDL_POWER"PVCCIO_CPU0"
BODY_TYPE"PLUMBING"
VOLTAGE"1.1V";
"G\NAC"1;
%"RES"
"2","(-4475,2150)","0","mstr_discrete","I32";
;
CDS_SEC"1"
LOCATION"R7D15"
VALUE"348"
TOLERANCE"1%"
WATTAGE"1/16W"
MATERIAL"CHIP"
PART_NUMBER"G21796-340"
PACK_TYPE"0402"
BOM_COST"DEBUG"
SEC_TYPE"0402"
SEC"1"
CDS_LOCATION"R7D15"
ROOM"PECI"
CDS_LIB"mstr_discrete";
"A"
$PN"1"8;
"B"
$PN"2"2;
%"GND"
"1","(-4475,1900)","0","mstr_symbols","I33";
;
BODY_TYPE"PLUMBING"
SIZE"1B"
CDS_LIB"mstr_symbols"
VOLTAGE"0.0V"
HDL_POWER"GND";
"A\NAC"2;
%"PI5A3157BC6E-GP"
"1","(-3400,2825)","0","w_hdl","I34";
;
CDS_SEC"1"
CDS_LOCATION"U7W1"
LOCATION"U7W1"
VALUE"PI5A3157BC6E-GP"
SEC_TYPE"DISCRET-GC2"
SEC"1"
PACK_TYPE"DISCRET-GC2"
PART_NUMBER"073.53157.000J"
CDS_LIB"w_hdl"
CDS_LMAN_SYM_OUTLINE"-150,150,150,-150";
"S"
$PN"6"11;
"VCC"
$PN"5"4;
"A"
$PN"4"10;
"B0"
$PN"3"8;
"GND"
$PN"2"5;
"B1"
$PN"1"9;
%"CAP_A"
"1","(-2725,3225)","0","dev_discrete","I36";
;
VOLTAGE"16V"
TOLERANCE"10%"
MATERIAL"X7R"
LOCATION"C7W1"
VALUE"0.1UF"
PART_NUMBER"A36096-030"
PACK_TYPE"0402V"
ROOM"PROC_SIDEBAND"
BOM_COST"PROC_SIDEBAND"
CDS_LIB"dev_discrete"
CDS_SEC"1"
SEC_TYPE"0402V"
SEC"1"
CDS_LOCATION"C7W1";
"B"
$PN"2"3;
"A"
$PN"1"4;
%"GND"
"1","(-2725,3025)","0","mstr_symbols","I37";
;
HDL_POWER"GND"
VOLTAGE"0.0V"
CDS_LIB"mstr_symbols"
SIZE"1B"
BODY_TYPE"PLUMBING";
"A\NAC"3;
%"P3V3_STBY"
"1","(-2875,3475)","0","mstr_symbols","I40";
;
SIZE"1B"
VOLTAGE"3.3V"
BODY_TYPE"PLUMBING"
HDL_POWER"P3V3_STBY"
CDS_LIB"mstr_symbols";
"G\NAC"4;
%"GND"
"1","(-3850,2825)","5","mstr_symbols","I41";
;
HDL_POWER"GND"
VOLTAGE"0.0V"
CDS_LIB"mstr_symbols"
SIZE"1B"
BODY_TYPE"PLUMBING";
"A\NAC"5;
%"RES"
"2","(-2400,2500)","0","mstr_discrete","I42";
;
CDS_SEC"1"
LOCATION"R7W2"
PACK_TYPE"0402"
PART_NUMBER"G21796-016"
MATERIAL"EMPTY"
WATTAGE"1/16W"
TOLERANCE"1%"
VALUE"10.0K"
CDS_LIB"mstr_discrete"
BOM_COST"SYS_CLOCK"
SEC_TYPE"0402"
SEC"1"
ROOM"DB1200ZL"
CDS_LOCATION"R7W2";
"A"
$PN"1"10;
"B"
$PN"2"6;
%"GND"
"1","(-2400,2250)","0","mstr_symbols","I43";
;
HDL_POWER"GND"
VOLTAGE"0.0V"
CDS_LIB"mstr_symbols"
SIZE"1B"
BODY_TYPE"PLUMBING";
"A\NAC"6;
%"P3V3_STBY"
"1","(-2400,3350)","0","mstr_symbols","I45";
;
CDS_LIB"mstr_symbols"
HDL_POWER"P3V3_STBY"
BODY_TYPE"PLUMBING"
VOLTAGE"3.3V"
SIZE"1B";
"G\NAC"7;
%"RES"
"2","(-2400,3150)","0","mstr_discrete","I46";
;
CDS_SEC"1"
LOCATION"R7W3"
VALUE"10.0K"
WATTAGE"1/16W"
MATERIAL"EMPTY"
TOLERANCE"1%"
PART_NUMBER"G21796-016"
PACK_TYPE"0402"
ROOM"DB1200ZL"
SEC"1"
SEC_TYPE"0402"
BOM_COST"SYS_CLOCK"
CDS_LIB"mstr_discrete"
CDS_LOCATION"R7W3";
"A"
$PN"1"7;
"B"
$PN"2"11;
END.
